(kicad_pcb
	(version 20260206)
	(generator "pcbnew")
	(generator_version "10.0")
	(general
		(thickness 1.6)
		(legacy_teardrops no)
	)
	(paper "A4")
	(title_block
		(title "Bryce Canyon_IOM_IOC_16318-2_OCP.brd")
		(comment 1 "Bryce Canyon / footprints 430-438 of 1605")
	)
	(layers
		(0 "F.Cu" signal "TOP")
		(4 "In1.Cu" signal "L2GND")
		(6 "In2.Cu" signal "L3")
		(8 "In3.Cu" signal "L4VCC")
		(10 "In4.Cu" signal "L5VCC")
		(12 "In5.Cu" signal "L6")
		(14 "In6.Cu" signal "L7GND")
		(2 "B.Cu" signal "BOTTOM")
		(9 "F.Adhes" user "F.Adhesive")
		(11 "B.Adhes" user "B.Adhesive")
		(13 "F.Paste" user "Package Geometry/Pastemask Top")
		(15 "B.Paste" user "Package Geometry/Pastemask Bottom")
		(5 "F.SilkS" user "Ref Des/Silkscreen Top")
		(7 "B.SilkS" user "Ref Des/Silkscreen Bottom")
		(1 "F.Mask" user "Board Geometry/Soldermask Top")
		(3 "B.Mask" user "Board Geometry/Soldermask Bottom")
		(17 "Dwgs.User" user "User.Drawings")
		(19 "Cmts.User" user "User.Comments")
		(21 "Eco1.User" user "User.Eco1")
		(23 "Eco2.User" user "User.Eco2")
		(25 "Edge.Cuts" user "Board Geometry/Outline")
		(27 "Margin" user)
		(31 "F.CrtYd" user "Package Geometry/Place Bound Top")
		(29 "B.CrtYd" user "Package Geometry/Place Bound Bottom")
		(35 "F.Fab" user "Ref Des/Assembly Top")
		(33 "B.Fab" user "Ref Des/Assembly Bottom")
	)
	(footprint ""
		(layer "F.Cu")
		(at 47.8536 -128.1684 180)
		(property "Reference" "R88"
			(at 0 0 180)
			(layer "F.SilkS")
			(hide yes)
			(effects
				(font
					(size 1.27 1.27)
				)
			)
		)
		(property "Value" "100KR2F-L1-GP"
			(at 0.064008 -3.993896 180)
			(unlocked yes)
			(layer "F.Fab")
			(hide yes)
			(effects
				(font
					(size 1.016 1.016)
					(thickness 0.1524)
				)
			)
		)
		(property "Device Type" "R402H16"
			(at 0.064008 -5.517896 180)
			(unlocked yes)
			(layer "F.Fab")
			(hide yes)
			(effects
				(font
					(size 1.016 1.016)
					(thickness 0.1524)
				)
			)
		)
		(duplicate_pad_numbers_are_jumpers no)
		(fp_line
			(start 0.508 -0.9398)
			(end -0.508 -0.9398)
			(stroke
				(width 0.1524)
				(type default)
			)
			(layer "F.SilkS")
		)
		(fp_line
			(start -0.508 -0.9398)
			(end -0.508 0.9398)
			(stroke
				(width 0.1524)
				(type default)
			)
			(layer "F.SilkS")
		)
		(fp_rect
			(start -0.508 0.9398)
			(end 0.508 -0.9398)
			(stroke
				(width 0)
				(type default)
			)
			(fill no)
			(layer "F.CrtYd")
		)
		(fp_rect
			(start -0.508 0.9398)
			(end 0.508 -0.9398)
			(stroke
				(width 0)
				(type default)
			)
			(fill no)
			(layer "F.Fab")
		)
		(pad "1" smd custom
			(at 0 -0.4445 180)
			(size 0.1397 0.1397)
			(layers "F.Cu" "F.Mask" "F.Paste")
			(net "SCC_LOC_FULL_PWR_EN")
			(options
				(clearance outline)
				(anchor circle)
			)
			(primitives
				(gr_poly
					(pts
						(arc
							(start -0.1778 -0.2794)
							(mid -0.249642 -0.249642)
							(end -0.2794 -0.1778)
						)
						(arc
							(start -0.2794 0.1778)
							(mid -0.249642 0.249642)
							(end -0.1778 0.2794)
						)
						(arc
							(start 0.1778 0.2794)
							(mid 0.249642 0.249642)
							(end 0.2794 0.1778)
						)
						(arc
							(start 0.2794 -0.1778)
							(mid 0.249642 -0.249642)
							(end 0.1778 -0.2794)
						)
					)
					(width 0)
					(fill yes)
				)
			)
		)
		(pad "2" smd custom
			(at 0 0.4445 180)
			(size 0.1397 0.1397)
			(layers "F.Cu" "F.Mask" "F.Paste")
			(net "GND")
			(options
				(clearance outline)
				(anchor circle)
			)
			(primitives
				(gr_poly
					(pts
						(arc
							(start -0.1778 -0.2794)
							(mid -0.249642 -0.249642)
							(end -0.2794 -0.1778)
						)
						(arc
							(start -0.2794 0.1778)
							(mid -0.249642 0.249642)
							(end -0.1778 0.2794)
						)
						(arc
							(start 0.1778 0.2794)
							(mid 0.249642 0.249642)
							(end 0.2794 0.1778)
						)
						(arc
							(start 0.2794 -0.1778)
							(mid 0.249642 -0.249642)
							(end 0.1778 -0.2794)
						)
					)
					(width 0)
					(fill yes)
				)
			)
		)
	)
	(footprint ""
		(layer "F.Cu")
		(at 94.488 -16.256 180)
		(property "Reference" "D18"
			(at 0 0 180)
			(layer "F.SilkS")
			(hide yes)
			(effects
				(font
					(size 1.27 1.27)
				)
			)
		)
		(property "Value" "PESD5V0F1BL-GP"
			(at 1.8923 -1.5621 180)
			(unlocked yes)
			(layer "F.Fab")
			(hide yes)
			(effects
				(font
					(size 1.016 1.016)
					(thickness 0.1524)
				)
			)
		)
		(property "Device Type" "SOD882-10D6-1H20"
			(at 1.8923 -3.0861 180)
			(unlocked yes)
			(layer "F.Fab")
			(hide yes)
			(effects
				(font
					(size 1.016 1.016)
					(thickness 0.1524)
				)
			)
		)
		(duplicate_pad_numbers_are_jumpers no)
		(fp_line
			(start -0.3048 -0.9271)
			(end 0.3048 -0.9271)
			(stroke
				(width 0.254)
				(type default)
			)
			(layer "F.SilkS")
		)
		(fp_rect
			(start -0.2921 0.4953)
			(end 0.2921 -0.4953)
			(stroke
				(width 0)
				(type default)
			)
			(fill no)
			(layer "F.CrtYd")
		)
		(fp_poly
			(pts
				(xy -0.4318 0.8001) (xy -0.4318 -0.266192) (xy -0.2921 -0.266192) (xy -0.2921 0.4953) (xy 0.2921 0.4953)
				(xy 0.2921 -0.4953) (xy -0.2921 -0.4953) (xy -0.2921 -0.2667) (xy -0.4318 -0.2667) (xy -0.4318 -0.8001)
				(xy 0.4318 -0.8001) (xy 0.4318 0.8001)
			)
			(stroke
				(width 0)
				(type default)
			)
			(fill no)
			(layer "F.CrtYd")
		)
		(fp_rect
			(start -0.4318 0.8001)
			(end 0.4318 -0.8001)
			(stroke
				(width 0)
				(type default)
			)
			(fill no)
			(layer "F.Fab")
		)
		(pad "1" smd custom
			(at 0 -0.4445 180)
			(size 0.1143 0.1143)
			(layers "F.Cu" "F.Mask" "F.Paste")
			(net "GND")
			(options
				(clearance outline)
				(anchor circle)
			)
			(primitives
				(gr_poly
					(pts
						(arc
							(start -0.2032 0.2286)
							(mid -0.275042 0.198842)
							(end -0.3048 0.127)
						)
						(arc
							(start -0.3048 -0.127)
							(mid -0.275042 -0.198842)
							(end -0.2032 -0.2286)
						)
						(arc
							(start 0.2032 -0.2286)
							(mid 0.275042 -0.198842)
							(end 0.3048 -0.127)
						)
						(arc
							(start 0.3048 0.127)
							(mid 0.275042 0.198842)
							(end 0.2032 0.2286)
						)
					)
					(width 0)
					(fill yes)
				)
			)
		)
		(pad "2" smd custom
			(at 0 0.4445 180)
			(size 0.1143 0.1143)
			(layers "F.Cu" "F.Mask" "F.Paste")
			(net "USB_P1_F_DP1")
			(options
				(clearance outline)
				(anchor circle)
			)
			(primitives
				(gr_poly
					(pts
						(arc
							(start 0.2032 -0.2286)
							(mid 0.275042 -0.198842)
							(end 0.3048 -0.127)
						)
						(arc
							(start 0.3048 0.127)
							(mid 0.275042 0.198842)
							(end 0.2032 0.2286)
						)
						(arc
							(start -0.2032 0.2286)
							(mid -0.275042 0.198842)
							(end -0.3048 0.127)
						)
						(arc
							(start -0.3048 -0.127)
							(mid -0.275042 -0.198842)
							(end -0.2032 -0.2286)
						)
					)
					(width 0)
					(fill yes)
				)
			)
		)
	)
	(footprint ""
		(layer "F.Cu")
		(at 23.88108 -186.560714 180)
		(property "Reference" "C171"
			(at 0 0 180)
			(layer "F.SilkS")
			(hide yes)
			(effects
				(font
					(size 1.27 1.27)
				)
			)
		)
		(property "Value" "SC10U16V5KX-7-GP-U"
			(at -0.0762 -6.1214 180)
			(unlocked yes)
			(layer "F.Fab")
			(hide yes)
			(effects
				(font
					(size 1.016 1.016)
					(thickness 0.1524)
				)
			)
		)
		(property "Device Type" "C805H58"
			(at -0.0762 -8.1534 180)
			(unlocked yes)
			(layer "F.Fab")
			(hide yes)
			(effects
				(font
					(size 1.016 1.016)
					(thickness 0.1524)
				)
			)
		)
		(duplicate_pad_numbers_are_jumpers no)
		(fp_line
			(start 0.635 0)
			(end -0.635 0)
			(stroke
				(width 0.508)
				(type default)
			)
			(layer "F.SilkS")
		)
		(fp_rect
			(start -0.9652 1.778)
			(end 0.9652 -1.778)
			(stroke
				(width 0)
				(type default)
			)
			(fill no)
			(layer "F.CrtYd")
		)
		(fp_poly
			(pts
				(xy -0.9652 -1.778) (xy 0.9652 -1.778) (xy 0.9652 1.778) (xy -0.9652 1.778)
			)
			(stroke
				(width 0)
				(type default)
			)
			(fill no)
			(layer "F.Fab")
		)
		(pad "1" smd rect
			(at 0 -0.9652 180)
			(size 1.397 1.143)
			(layers "F.Cu" "F.Mask" "F.Paste")
			(net "P12V_STBY_VIN_PU2")
		)
		(pad "2" smd rect
			(at 0 0.9652 180)
			(size 1.397 1.143)
			(layers "F.Cu" "F.Mask" "F.Paste")
			(net "GND")
		)
	)
	(footprint ""
		(layer "F.Cu")
		(at 76.1746 -148.336 180)
		(property "Reference" "C75"
			(at 0 0 180)
			(layer "F.SilkS")
			(hide yes)
			(effects
				(font
					(size 1.27 1.27)
				)
			)
		)
		(property "Value" "SCD1U16V2KX-3GP"
			(at 1.1811 -2.7051 180)
			(unlocked yes)
			(layer "F.Fab")
			(hide yes)
			(effects
				(font
					(size 1.016 1.016)
					(thickness 0.1524)
				)
			)
		)
		(property "Device Type" "C402H22"
			(at 1.1811 -4.2291 180)
			(unlocked yes)
			(layer "F.Fab")
			(hide yes)
			(effects
				(font
					(size 1.016 1.016)
					(thickness 0.1524)
				)
			)
		)
		(duplicate_pad_numbers_are_jumpers no)
		(fp_rect
			(start -0.4318 0.9525)
			(end 0.4318 -0.9525)
			(stroke
				(width 0)
				(type default)
			)
			(fill no)
			(layer "F.CrtYd")
		)
		(fp_rect
			(start -0.4318 0.9525)
			(end 0.4318 -0.9525)
			(stroke
				(width 0)
				(type default)
			)
			(fill no)
			(layer "F.Fab")
		)
		(pad "1" smd custom
			(at 0 -0.4445 180)
			(size 0.1524 0.1524)
			(layers "F.Cu" "F.Mask" "F.Paste")
			(net "P3V3_STBY")
			(options
				(clearance outline)
				(anchor circle)
			)
			(primitives
				(gr_poly
					(pts
						(arc
							(start 0.3048 -0.2032)
							(mid 0.275042 -0.275042)
							(end 0.2032 -0.3048)
						)
						(arc
							(start -0.2032 -0.3048)
							(mid -0.275042 -0.275042)
							(end -0.3048 -0.2032)
						)
						(arc
							(start -0.3048 0.2032)
							(mid -0.275042 0.275042)
							(end -0.2032 0.3048)
						)
						(arc
							(start 0.2032 0.3048)
							(mid 0.275042 0.275042)
							(end 0.3048 0.2032)
						)
					)
					(width 0)
					(fill yes)
				)
			)
		)
		(pad "2" smd custom
			(at 0 0.4445 180)
			(size 0.1524 0.1524)
			(layers "F.Cu" "F.Mask" "F.Paste")
			(net "GND")
			(options
				(clearance outline)
				(anchor circle)
			)
			(primitives
				(gr_poly
					(pts
						(arc
							(start 0.3048 -0.2032)
							(mid 0.275042 -0.275042)
							(end 0.2032 -0.3048)
						)
						(arc
							(start -0.2032 -0.3048)
							(mid -0.275042 -0.275042)
							(end -0.3048 -0.2032)
						)
						(arc
							(start -0.3048 0.2032)
							(mid -0.275042 0.275042)
							(end -0.2032 0.3048)
						)
						(arc
							(start 0.2032 0.3048)
							(mid 0.275042 0.275042)
							(end 0.3048 0.2032)
						)
					)
					(width 0)
					(fill yes)
				)
			)
		)
	)
	(footprint ""
		(layer "F.Cu")
		(at 161.203894 -93.740224 180)
		(property "Reference" "R690"
			(at 0 0 180)
			(layer "F.SilkS")
			(hide yes)
			(effects
				(font
					(size 1.27 1.27)
				)
			)
		)
		(property "Value" "2K2R2F-GP"
			(at 0.064008 -3.993896 180)
			(unlocked yes)
			(layer "F.Fab")
			(hide yes)
			(effects
				(font
					(size 1.016 1.016)
					(thickness 0.1524)
				)
			)
		)
		(property "Device Type" "R402H16"
			(at 0.064008 -5.517896 180)
			(unlocked yes)
			(layer "F.Fab")
			(hide yes)
			(effects
				(font
					(size 1.016 1.016)
					(thickness 0.1524)
				)
			)
		)
		(duplicate_pad_numbers_are_jumpers no)
		(fp_line
			(start 0.508 -0.9398)
			(end -0.508 -0.9398)
			(stroke
				(width 0.1524)
				(type default)
			)
			(layer "F.SilkS")
		)
		(fp_line
			(start -0.508 -0.9398)
			(end -0.508 0.9398)
			(stroke
				(width 0.1524)
				(type default)
			)
			(layer "F.SilkS")
		)
		(fp_rect
			(start -0.508 0.9398)
			(end 0.508 -0.9398)
			(stroke
				(width 0)
				(type default)
			)
			(fill no)
			(layer "F.CrtYd")
		)
		(fp_rect
			(start -0.508 0.9398)
			(end 0.508 -0.9398)
			(stroke
				(width 0)
				(type default)
			)
			(fill no)
			(layer "F.Fab")
		)
		(pad "1" smd custom
			(at 0 -0.4445 180)
			(size 0.1397 0.1397)
			(layers "F.Cu" "F.Mask" "F.Paste")
			(net "I2C_IOC_SCL")
			(options
				(clearance outline)
				(anchor circle)
			)
			(primitives
				(gr_poly
					(pts
						(arc
							(start -0.1778 -0.2794)
							(mid -0.249642 -0.249642)
							(end -0.2794 -0.1778)
						)
						(arc
							(start -0.2794 0.1778)
							(mid -0.249642 0.249642)
							(end -0.1778 0.2794)
						)
						(arc
							(start 0.1778 0.2794)
							(mid 0.249642 0.249642)
							(end 0.2794 0.1778)
						)
						(arc
							(start 0.2794 -0.1778)
							(mid 0.249642 -0.249642)
							(end 0.1778 -0.2794)
						)
					)
					(width 0)
					(fill yes)
				)
			)
		)
		(pad "2" smd custom
			(at 0 0.4445 180)
			(size 0.1397 0.1397)
			(layers "F.Cu" "F.Mask" "F.Paste")
			(net "P3V3_STBY")
			(options
				(clearance outline)
				(anchor circle)
			)
			(primitives
				(gr_poly
					(pts
						(arc
							(start -0.1778 -0.2794)
							(mid -0.249642 -0.249642)
							(end -0.2794 -0.1778)
						)
						(arc
							(start -0.2794 0.1778)
							(mid -0.249642 0.249642)
							(end -0.1778 0.2794)
						)
						(arc
							(start 0.1778 0.2794)
							(mid 0.249642 0.249642)
							(end 0.2794 0.1778)
						)
						(arc
							(start 0.2794 -0.1778)
							(mid 0.249642 -0.249642)
							(end 0.1778 -0.2794)
						)
					)
					(width 0)
					(fill yes)
				)
			)
		)
	)
	(footprint ""
		(layer "F.Cu")
		(at 23.0759 -173.267116 90)
		(property "Reference" "C231"
			(at 0 0 90)
			(layer "F.SilkS")
			(hide yes)
			(effects
				(font
					(size 1.27 1.27)
				)
			)
		)
		(property "Value" "SC10U6D3V5KX-4GP"
			(at -0.0762 -6.1214 90)
			(unlocked yes)
			(layer "F.Fab")
			(hide yes)
			(effects
				(font
					(size 1.016 1.016)
					(thickness 0.1524)
				)
			)
		)
		(property "Device Type" "C805H58"
			(at -0.0762 -8.1534 90)
			(unlocked yes)
			(layer "F.Fab")
			(hide yes)
			(effects
				(font
					(size 1.016 1.016)
					(thickness 0.1524)
				)
			)
		)
		(duplicate_pad_numbers_are_jumpers no)
		(fp_line
			(start 0.635 0)
			(end -0.635 0)
			(stroke
				(width 0.508)
				(type default)
			)
			(layer "F.SilkS")
		)
		(fp_rect
			(start -0.9652 1.778)
			(end 0.9652 -1.778)
			(stroke
				(width 0)
				(type default)
			)
			(fill no)
			(layer "F.CrtYd")
		)
		(fp_poly
			(pts
				(xy -0.9652 -1.778) (xy 0.9652 -1.778) (xy 0.9652 1.778) (xy -0.9652 1.778)
			)
			(stroke
				(width 0)
				(type default)
			)
			(fill no)
			(layer "F.Fab")
		)
		(pad "1" smd rect
			(at 0 -0.9652 90)
			(size 1.397 1.143)
			(layers "F.Cu" "F.Mask" "F.Paste")
			(net "P1V8_STBY")
		)
		(pad "2" smd rect
			(at 0 0.9652 90)
			(size 1.397 1.143)
			(layers "F.Cu" "F.Mask" "F.Paste")
			(net "GND")
		)
	)
	(footprint ""
		(layer "F.Cu")
		(at 93.599 -150.3426 -90)
		(property "Reference" "TP5"
			(at 0 0 270)
			(layer "F.SilkS")
			(hide yes)
			(effects
				(font
					(size 1.27 1.27)
				)
			)
		)
		(property "Value" "TPAD28-2-GP"
			(at -0.0127 -1.6637 270)
			(unlocked yes)
			(layer "F.Fab")
			(hide yes)
			(effects
				(font
					(size 1.016 1.016)
					(thickness 0.1524)
				)
			)
		)
		(property "Device Type" "TPAD28"
			(at -0.0127 -3.1877 270)
			(unlocked yes)
			(layer "F.Fab")
			(hide yes)
			(effects
				(font
					(size 1.016 1.016)
					(thickness 0.1524)
				)
			)
		)
		(duplicate_pad_numbers_are_jumpers no)
		(fp_poly
			(pts
				(arc
					(start 0 -0.3556)
					(mid 0 0.3556)
					(end 0 -0.3556)
				)
			)
			(stroke
				(width 0)
				(type default)
			)
			(fill no)
			(layer "F.CrtYd")
		)
		(fp_poly
			(pts
				(arc
					(start 0 -0.6096)
					(mid 0 0.6096)
					(end 0 -0.6096)
				)
			)
			(stroke
				(width 0)
				(type default)
			)
			(fill no)
			(layer "F.Fab")
		)
		(pad "1" smd circle
			(at 0 0 270)
			(size 0.7112 0.7112)
			(layers "F.Cu" "F.Mask" "F.Paste")
			(net "CRFILT")
		)
	)
	(footprint ""
		(layer "F.Cu")
		(at 89.41562 -178.46548 -90)
		(property "Reference" "C136"
			(at 0 0 270)
			(layer "F.SilkS")
			(hide yes)
			(effects
				(font
					(size 1.27 1.27)
				)
			)
		)
		(property "Value" "SCD1U16V2KX-3GP"
			(at 1.1811 -2.7051 270)
			(unlocked yes)
			(layer "F.Fab")
			(hide yes)
			(effects
				(font
					(size 1.016 1.016)
					(thickness 0.1524)
				)
			)
		)
		(property "Device Type" "C402H22"
			(at 1.1811 -4.2291 270)
			(unlocked yes)
			(layer "F.Fab")
			(hide yes)
			(effects
				(font
					(size 1.016 1.016)
					(thickness 0.1524)
				)
			)
		)
		(duplicate_pad_numbers_are_jumpers no)
		(fp_rect
			(start -0.4318 0.9525)
			(end 0.4318 -0.9525)
			(stroke
				(width 0)
				(type default)
			)
			(fill no)
			(layer "F.CrtYd")
		)
		(fp_rect
			(start -0.4318 0.9525)
			(end 0.4318 -0.9525)
			(stroke
				(width 0)
				(type default)
			)
			(fill no)
			(layer "F.Fab")
		)
		(pad "1" smd custom
			(at 0 -0.4445 270)
			(size 0.1524 0.1524)
			(layers "F.Cu" "F.Mask" "F.Paste")
			(net "P3V3_STBY")
			(options
				(clearance outline)
				(anchor circle)
			)
			(primitives
				(gr_poly
					(pts
						(arc
							(start 0.3048 -0.2032)
							(mid 0.275042 -0.275042)
							(end 0.2032 -0.3048)
						)
						(arc
							(start -0.2032 -0.3048)
							(mid -0.275042 -0.275042)
							(end -0.3048 -0.2032)
						)
						(arc
							(start -0.3048 0.2032)
							(mid -0.275042 0.275042)
							(end -0.2032 0.3048)
						)
						(arc
							(start 0.2032 0.3048)
							(mid 0.275042 0.275042)
							(end 0.3048 0.2032)
						)
					)
					(width 0)
					(fill yes)
				)
			)
		)
		(pad "2" smd custom
			(at 0 0.4445 270)
			(size 0.1524 0.1524)
			(layers "F.Cu" "F.Mask" "F.Paste")
			(net "GND")
			(options
				(clearance outline)
				(anchor circle)
			)
			(primitives
				(gr_poly
					(pts
						(arc
							(start 0.3048 -0.2032)
							(mid 0.275042 -0.275042)
							(end 0.2032 -0.3048)
						)
						(arc
							(start -0.2032 -0.3048)
							(mid -0.275042 -0.275042)
							(end -0.3048 -0.2032)
						)
						(arc
							(start -0.3048 0.2032)
							(mid -0.275042 0.275042)
							(end -0.2032 0.3048)
						)
						(arc
							(start 0.2032 0.3048)
							(mid 0.275042 0.275042)
							(end 0.3048 0.2032)
						)
					)
					(width 0)
					(fill yes)
				)
			)
		)
	)
	(footprint ""
		(layer "F.Cu")
		(at 182.0291 -45.5422 180)
		(property "Reference" "R661"
			(at 0 0 180)
			(layer "F.SilkS")
			(hide yes)
			(effects
				(font
					(size 1.27 1.27)
				)
			)
		)
		(property "Value" "10KR2F-2-GP"
			(at 0.064008 -3.993896 180)
			(unlocked yes)
			(layer "F.Fab")
			(hide yes)
			(effects
				(font
					(size 1.016 1.016)
					(thickness 0.1524)
				)
			)
		)
		(property "Device Type" "R402H16"
			(at 0.064008 -5.517896 180)
			(unlocked yes)
			(layer "F.Fab")
			(hide yes)
			(effects
				(font
					(size 1.016 1.016)
					(thickness 0.1524)
				)
			)
		)
		(duplicate_pad_numbers_are_jumpers no)
		(fp_line
			(start 0.508 -0.9398)
			(end -0.508 -0.9398)
			(stroke
				(width 0.1524)
				(type default)
			)
			(layer "F.SilkS")
		)
		(fp_line
			(start -0.508 -0.9398)
			(end -0.508 0.9398)
			(stroke
				(width 0.1524)
				(type default)
			)
			(layer "F.SilkS")
		)
		(fp_rect
			(start -0.508 0.9398)
			(end 0.508 -0.9398)
			(stroke
				(width 0)
				(type default)
			)
			(fill no)
			(layer "F.CrtYd")
		)
		(fp_rect
			(start -0.508 0.9398)
			(end 0.508 -0.9398)
			(stroke
				(width 0)
				(type default)
			)
			(fill no)
			(layer "F.Fab")
		)
		(pad "1" smd custom
			(at 0 -0.4445 180)
			(size 0.1397 0.1397)
			(layers "F.Cu" "F.Mask" "F.Paste")
			(net "P1V8")
			(options
				(clearance outline)
				(anchor circle)
			)
			(primitives
				(gr_poly
					(pts
						(arc
							(start -0.1778 -0.2794)
							(mid -0.249642 -0.249642)
							(end -0.2794 -0.1778)
						)
						(arc
							(start -0.2794 0.1778)
							(mid -0.249642 0.249642)
							(end -0.1778 0.2794)
						)
						(arc
							(start 0.1778 0.2794)
							(mid 0.249642 0.249642)
							(end 0.2794 0.1778)
						)
						(arc
							(start 0.2794 -0.1778)
							(mid 0.249642 -0.249642)
							(end 0.1778 -0.2794)
						)
					)
					(width 0)
					(fill yes)
				)
			)
		)
		(pad "2" smd custom
			(at 0 0.4445 180)
			(size 0.1397 0.1397)
			(layers "F.Cu" "F.Mask" "F.Paste")
			(net "XM_ADDR_4")
			(options
				(clearance outline)
				(anchor circle)
			)
			(primitives
				(gr_poly
					(pts
						(arc
							(start -0.1778 -0.2794)
							(mid -0.249642 -0.249642)
							(end -0.2794 -0.1778)
						)
						(arc
							(start -0.2794 0.1778)
							(mid -0.249642 0.249642)
							(end -0.1778 0.2794)
						)
						(arc
							(start 0.1778 0.2794)
							(mid 0.249642 0.249642)
							(end 0.2794 0.1778)
						)
						(arc
							(start 0.2794 -0.1778)
							(mid 0.249642 -0.249642)
							(end 0.1778 -0.2794)
						)
					)
					(width 0)
					(fill yes)
				)
			)
		)
	)
)
